(kicad_pcb
	(version 20260206)
	(generator "pcbnew")
	(generator_version "10.0")
	(general
		(thickness 1.6)
		(legacy_teardrops no)
	)
	(paper "A4")
	(title_block
		(title "04192023_DAF0TMB3IC0_F0TG_MB_C_brd_V02_OCP.brd")
		(comment 1 "Grand Teton / footprints 4-10 of 8354")
	)
	(layers
		(0 "F.Cu" signal "TOP")
		(4 "In1.Cu" signal "GND")
		(6 "In2.Cu" signal "IN1")
		(8 "In3.Cu" signal "GND1")
		(10 "In4.Cu" signal "IN2")
		(12 "In5.Cu" signal "GND2")
		(14 "In6.Cu" signal "IN3")
		(16 "In7.Cu" signal "GND3")
		(18 "In8.Cu" signal "VCC")
		(20 "In9.Cu" signal "VCC1")
		(22 "In10.Cu" signal "GND4")
		(24 "In11.Cu" signal "IN4")
		(26 "In12.Cu" signal "GND5")
		(28 "In13.Cu" signal "IN5")
		(30 "In14.Cu" signal "GND6")
		(32 "In15.Cu" signal "IN6")
		(34 "In16.Cu" signal "GND7")
		(2 "B.Cu" signal "BOTTOM")
		(9 "F.Adhes" user "F.Adhesive")
		(11 "B.Adhes" user "B.Adhesive")
		(13 "F.Paste" user "Package Geometry/Pastemask Top")
		(15 "B.Paste" user "Package Geometry/Pastemask Bottom")
		(5 "F.SilkS" user "Ref Des/Silkscreen Top")
		(7 "B.SilkS" user "Ref Des/Silkscreen Bottom")
		(1 "F.Mask" user "Board Geometry/Soldermask Top")
		(3 "B.Mask" user "Board Geometry/Soldermask Bottom")
		(17 "Dwgs.User" user "User.Drawings")
		(19 "Cmts.User" user "User.Comments")
		(21 "Eco1.User" user "User.Eco1")
		(23 "Eco2.User" user "User.Eco2")
		(25 "Edge.Cuts" user "Board Geometry/Outline")
		(27 "Margin" user)
		(31 "F.CrtYd" user "Package Geometry/Place Bound Top")
		(29 "B.CrtYd" user "Package Geometry/Place Bound Bottom")
		(35 "F.Fab" user "Ref Des/Assembly Top")
		(33 "B.Fab" user "Ref Des/Assembly Bottom")
	)
	(footprint ""
		(layer "F.Cu")
		(at 456.051666 -380.13767 -90)
		(property "Reference" "PC6573"
			(at 4.62534 2.026666 0)
			(unlocked yes)
			(layer "F.SilkS")
			(effects
				(font
					(size 0.7874 0.5842)
					(thickness 0.1524)
				)
				(justify left)
			)
		)
		(property "Value" ""
			(at 0 0 270)
			(layer "F.Fab")
			(effects
				(font
					(size 1.27 1.27)
				)
			)
		)
		(duplicate_pad_numbers_are_jumpers no)
		(fp_line
			(start -1.988058 2.750058)
			(end 2.750058 2.750058)
			(stroke
				(width 0.1524)
				(type default)
			)
			(layer "F.SilkS")
		)
		(fp_line
			(start 2.750058 2.750058)
			(end 2.750058 0.9398)
			(stroke
				(width 0.1524)
				(type default)
			)
			(layer "F.SilkS")
		)
		(fp_line
			(start -2.750058 1.988058)
			(end -1.988058 2.750058)
			(stroke
				(width 0.1524)
				(type default)
			)
			(layer "F.SilkS")
		)
		(fp_line
			(start -2.750058 0.9398)
			(end -2.750058 1.988058)
			(stroke
				(width 0.1524)
				(type default)
			)
			(layer "F.SilkS")
		)
		(fp_line
			(start 2.750058 -0.9398)
			(end 2.750058 -2.750058)
			(stroke
				(width 0.1524)
				(type default)
			)
			(layer "F.SilkS")
		)
		(fp_line
			(start -2.750058 -1.988058)
			(end -2.750058 -0.9398)
			(stroke
				(width 0.1524)
				(type default)
			)
			(layer "F.SilkS")
		)
		(fp_line
			(start -1.988058 -2.750058)
			(end -2.750058 -1.988058)
			(stroke
				(width 0.1524)
				(type default)
			)
			(layer "F.SilkS")
		)
		(fp_line
			(start 2.750058 -2.750058)
			(end -1.988058 -2.750058)
			(stroke
				(width 0.1524)
				(type default)
			)
			(layer "F.SilkS")
		)
		(fp_line
			(start -2.750058 2.750058)
			(end 2.750058 2.750058)
			(stroke
				(width 0.1)
				(type default)
			)
			(layer "F.Fab")
		)
		(fp_line
			(start 2.750058 2.750058)
			(end 2.750058 -2.750058)
			(stroke
				(width 0.1)
				(type default)
			)
			(layer "F.Fab")
		)
		(fp_line
			(start -2.750058 -2.750058)
			(end -2.750058 2.750058)
			(stroke
				(width 0.1)
				(type default)
			)
			(layer "F.Fab")
		)
		(fp_line
			(start 2.750058 -2.750058)
			(end -2.750058 -2.750058)
			(stroke
				(width 0.1)
				(type default)
			)
			(layer "F.Fab")
		)
		(pad "1" smd rect
			(at -2.199894 0)
			(size 1.6002 3.0226)
			(layers "F.Cu" "F.Mask" "F.Paste")
			(net "P0V9_CPU0_RT_2D")
		)
		(pad "2" smd rect
			(at 2.199894 0)
			(size 1.6002 3.0226)
			(layers "F.Cu" "F.Mask" "F.Paste")
			(net "GND")
		)
	)
	(footprint ""
		(layer "F.Cu")
		(at 271.328134 -421.23868 90)
		(property "Reference" "R3907"
			(at 0 0 90)
			(layer "F.SilkS")
			(hide yes)
			(effects
				(font
					(size 1.27 1.27)
				)
			)
		)
		(property "Value" ""
			(at 0 0 90)
			(layer "F.Fab")
			(effects
				(font
					(size 1.27 1.27)
				)
			)
		)
		(duplicate_pad_numbers_are_jumpers no)
		(fp_line
			(start 0.7874 -0.4064)
			(end 0.7874 0.4064)
			(stroke
				(width 0.1524)
				(type default)
			)
			(layer "F.SilkS")
		)
		(fp_line
			(start -0.7874 -0.4064)
			(end 0.7874 -0.4064)
			(stroke
				(width 0.1524)
				(type default)
			)
			(layer "F.SilkS")
		)
		(fp_line
			(start 0.7874 0.4064)
			(end -0.7874 0.4064)
			(stroke
				(width 0.1524)
				(type default)
			)
			(layer "F.SilkS")
		)
		(fp_line
			(start -0.7874 0.4064)
			(end -0.7874 -0.4064)
			(stroke
				(width 0.1524)
				(type default)
			)
			(layer "F.SilkS")
		)
		(fp_line
			(start -0.12065 -0.305054)
			(end -0.12065 -0.2794)
			(stroke
				(width 0.1)
				(type default)
			)
			(layer "F.Fab")
		)
		(fp_line
			(start -0.67945 -0.305054)
			(end -0.12065 -0.305054)
			(stroke
				(width 0.1)
				(type default)
			)
			(layer "F.Fab")
		)
		(fp_line
			(start 0.67945 -0.3048)
			(end 0.67945 0.3048)
			(stroke
				(width 0.1)
				(type default)
			)
			(layer "F.Fab")
		)
		(fp_line
			(start 0.12065 -0.3048)
			(end 0.67945 -0.3048)
			(stroke
				(width 0.1)
				(type default)
			)
			(layer "F.Fab")
		)
		(fp_line
			(start 0.12065 -0.2794)
			(end 0.12065 -0.3048)
			(stroke
				(width 0.1)
				(type default)
			)
			(layer "F.Fab")
		)
		(fp_line
			(start -0.12065 -0.2794)
			(end 0.12065 -0.2794)
			(stroke
				(width 0.1)
				(type default)
			)
			(layer "F.Fab")
		)
		(fp_line
			(start 0.120396 0.2794)
			(end -0.12065 0.2794)
			(stroke
				(width 0.1)
				(type default)
			)
			(layer "F.Fab")
		)
		(fp_line
			(start -0.12065 0.2794)
			(end -0.12065 0.3048)
			(stroke
				(width 0.1)
				(type default)
			)
			(layer "F.Fab")
		)
		(fp_line
			(start 0.67945 0.3048)
			(end 0.120396 0.3048)
			(stroke
				(width 0.1)
				(type default)
			)
			(layer "F.Fab")
		)
		(fp_line
			(start 0.120396 0.3048)
			(end 0.120396 0.2794)
			(stroke
				(width 0.1)
				(type default)
			)
			(layer "F.Fab")
		)
		(fp_line
			(start -0.12065 0.3048)
			(end -0.67945 0.3048)
			(stroke
				(width 0.1)
				(type default)
			)
			(layer "F.Fab")
		)
		(fp_line
			(start -0.67945 0.3048)
			(end -0.67945 -0.305054)
			(stroke
				(width 0.1)
				(type default)
			)
			(layer "F.Fab")
		)
		(pad "1" smd circle
			(at -0.40005 0 90)
			(size 0 0)
			(layers "F.Cu" "F.Mask" "F.Paste")
			(net "PDB_PRSNT_R_N")
		)
		(pad "2" smd circle
			(at 0.40005 0 90)
			(size 0 0)
			(layers "F.Cu" "F.Mask" "F.Paste")
			(net "GND")
		)
	)
	(footprint ""
		(layer "F.Cu")
		(at 327.951084 -349.43161 180)
		(property "Reference" "PC101"
			(at -0.199644 -2.938272 0)
			(unlocked yes)
			(layer "F.SilkS")
			(effects
				(font
					(size 0.7874 0.5842)
					(thickness 0.1524)
				)
				(justify left)
			)
		)
		(property "Value" ""
			(at 0 0 180)
			(layer "F.Fab")
			(effects
				(font
					(size 1.27 1.27)
				)
			)
		)
		(duplicate_pad_numbers_are_jumpers no)
		(fp_line
			(start -3.400044 1.249934)
			(end 3.400044 1.249934)
			(stroke
				(width 0.1524)
				(type default)
			)
			(layer "F.SilkS")
		)
		(fp_circle
			(center 0 1.249934)
			(end -3.400044 1.249934)
			(stroke
				(width 0.1524)
				(type default)
			)
			(fill no)
			(layer "F.SilkS")
		)
		(fp_poly
			(pts
				(arc
					(start 3.400044 1.249934)
					(mid 0 4.649978)
					(end -3.400044 1.249934)
				)
			)
			(stroke
				(width 0)
				(type default)
			)
			(fill yes)
			(layer "F.SilkS")
		)
		(fp_circle
			(center 0 1.249934)
			(end -3.400044 1.249934)
			(stroke
				(width 0.1)
				(type default)
			)
			(fill no)
			(layer "F.Fab")
		)
		(pad "1" thru_hole rect
			(at 0 0 180)
			(size 1.524 1.524)
			(drill 1.016)
			(layers "*.Cu" "*.Mask")
			(remove_unused_layers no)
			(net "SW_P12V_AUX_PVDDCR_CPU1_P0_FLT")
			(clearance 0)
			(padstack
				(mode front_inner_back)
				(layer "Inner"
					(shape circle)
					(size 1.524 1.524)
					(clearance 0)
				)
				(layer "B.Cu"
					(shape rect)
					(size 1.524 1.524)
					(clearance 0)
				)
			)
		)
		(pad "2" thru_hole circle
			(at 0 2.500122 180)
			(size 1.524 1.524)
			(drill 1.016)
			(layers "*.Cu" "*.Mask")
			(remove_unused_layers no)
			(net "GND")
			(clearance 0)
		)
	)
	(footprint ""
		(layer "F.Cu")
		(at 183.769 -100.294948 -90)
		(property "Reference" "R270"
			(at 0 0 270)
			(layer "F.SilkS")
			(hide yes)
			(effects
				(font
					(size 1.27 1.27)
				)
			)
		)
		(property "Value" ""
			(at 0 0 270)
			(layer "F.Fab")
			(effects
				(font
					(size 1.27 1.27)
				)
			)
		)
		(duplicate_pad_numbers_are_jumpers no)
		(fp_line
			(start -0.7874 0.4064)
			(end -0.7874 -0.4064)
			(stroke
				(width 0.1524)
				(type default)
			)
			(layer "F.SilkS")
		)
		(fp_line
			(start 0.7874 0.4064)
			(end -0.7874 0.4064)
			(stroke
				(width 0.1524)
				(type default)
			)
			(layer "F.SilkS")
		)
		(fp_line
			(start -0.7874 -0.4064)
			(end 0.7874 -0.4064)
			(stroke
				(width 0.1524)
				(type default)
			)
			(layer "F.SilkS")
		)
		(fp_line
			(start 0.7874 -0.4064)
			(end 0.7874 0.4064)
			(stroke
				(width 0.1524)
				(type default)
			)
			(layer "F.SilkS")
		)
		(fp_line
			(start -0.67945 0.3048)
			(end -0.67945 -0.305054)
			(stroke
				(width 0.1)
				(type default)
			)
			(layer "F.Fab")
		)
		(fp_line
			(start -0.12065 0.3048)
			(end -0.67945 0.3048)
			(stroke
				(width 0.1)
				(type default)
			)
			(layer "F.Fab")
		)
		(fp_line
			(start 0.120396 0.3048)
			(end 0.120396 0.2794)
			(stroke
				(width 0.1)
				(type default)
			)
			(layer "F.Fab")
		)
		(fp_line
			(start 0.67945 0.3048)
			(end 0.120396 0.3048)
			(stroke
				(width 0.1)
				(type default)
			)
			(layer "F.Fab")
		)
		(fp_line
			(start -0.12065 0.2794)
			(end -0.12065 0.3048)
			(stroke
				(width 0.1)
				(type default)
			)
			(layer "F.Fab")
		)
		(fp_line
			(start 0.120396 0.2794)
			(end -0.12065 0.2794)
			(stroke
				(width 0.1)
				(type default)
			)
			(layer "F.Fab")
		)
		(fp_line
			(start -0.12065 -0.2794)
			(end 0.12065 -0.2794)
			(stroke
				(width 0.1)
				(type default)
			)
			(layer "F.Fab")
		)
		(fp_line
			(start 0.12065 -0.2794)
			(end 0.12065 -0.3048)
			(stroke
				(width 0.1)
				(type default)
			)
			(layer "F.Fab")
		)
		(fp_line
			(start 0.12065 -0.3048)
			(end 0.67945 -0.3048)
			(stroke
				(width 0.1)
				(type default)
			)
			(layer "F.Fab")
		)
		(fp_line
			(start 0.67945 -0.3048)
			(end 0.67945 0.3048)
			(stroke
				(width 0.1)
				(type default)
			)
			(layer "F.Fab")
		)
		(fp_line
			(start -0.67945 -0.305054)
			(end -0.12065 -0.305054)
			(stroke
				(width 0.1)
				(type default)
			)
			(layer "F.Fab")
		)
		(fp_line
			(start -0.12065 -0.305054)
			(end -0.12065 -0.2794)
			(stroke
				(width 0.1)
				(type default)
			)
			(layer "F.Fab")
		)
		(pad "1" smd circle
			(at -0.40005 0 270)
			(size 0 0)
			(layers "F.Cu" "F.Mask" "F.Paste")
			(net "FM_CPU1_PROCHOT_R_N")
		)
		(pad "2" smd circle
			(at 0.40005 0 270)
			(size 0 0)
			(layers "F.Cu" "F.Mask" "F.Paste")
			(net "CPU1_PROCHOT_N")
		)
	)
	(footprint ""
		(layer "F.Cu")
		(at 299.29836 -119.67591 90)
		(property "Reference" "R3586"
			(at 0 0 90)
			(layer "F.SilkS")
			(hide yes)
			(effects
				(font
					(size 1.27 1.27)
				)
			)
		)
		(property "Value" ""
			(at 0 0 90)
			(layer "F.Fab")
			(effects
				(font
					(size 1.27 1.27)
				)
			)
		)
		(duplicate_pad_numbers_are_jumpers no)
		(fp_line
			(start 0.7874 -0.4064)
			(end 0.7874 0.4064)
			(stroke
				(width 0.1524)
				(type default)
			)
			(layer "F.SilkS")
		)
		(fp_line
			(start -0.7874 -0.4064)
			(end 0.7874 -0.4064)
			(stroke
				(width 0.1524)
				(type default)
			)
			(layer "F.SilkS")
		)
		(fp_line
			(start 0.7874 0.4064)
			(end -0.7874 0.4064)
			(stroke
				(width 0.1524)
				(type default)
			)
			(layer "F.SilkS")
		)
		(fp_line
			(start -0.7874 0.4064)
			(end -0.7874 -0.4064)
			(stroke
				(width 0.1524)
				(type default)
			)
			(layer "F.SilkS")
		)
		(fp_line
			(start -0.12065 -0.305054)
			(end -0.12065 -0.2794)
			(stroke
				(width 0.1)
				(type default)
			)
			(layer "F.Fab")
		)
		(fp_line
			(start -0.67945 -0.305054)
			(end -0.12065 -0.305054)
			(stroke
				(width 0.1)
				(type default)
			)
			(layer "F.Fab")
		)
		(fp_line
			(start 0.67945 -0.3048)
			(end 0.67945 0.3048)
			(stroke
				(width 0.1)
				(type default)
			)
			(layer "F.Fab")
		)
		(fp_line
			(start 0.12065 -0.3048)
			(end 0.67945 -0.3048)
			(stroke
				(width 0.1)
				(type default)
			)
			(layer "F.Fab")
		)
		(fp_line
			(start 0.12065 -0.2794)
			(end 0.12065 -0.3048)
			(stroke
				(width 0.1)
				(type default)
			)
			(layer "F.Fab")
		)
		(fp_line
			(start -0.12065 -0.2794)
			(end 0.12065 -0.2794)
			(stroke
				(width 0.1)
				(type default)
			)
			(layer "F.Fab")
		)
		(fp_line
			(start 0.120396 0.2794)
			(end -0.12065 0.2794)
			(stroke
				(width 0.1)
				(type default)
			)
			(layer "F.Fab")
		)
		(fp_line
			(start -0.12065 0.2794)
			(end -0.12065 0.3048)
			(stroke
				(width 0.1)
				(type default)
			)
			(layer "F.Fab")
		)
		(fp_line
			(start 0.67945 0.3048)
			(end 0.120396 0.3048)
			(stroke
				(width 0.1)
				(type default)
			)
			(layer "F.Fab")
		)
		(fp_line
			(start 0.120396 0.3048)
			(end 0.120396 0.2794)
			(stroke
				(width 0.1)
				(type default)
			)
			(layer "F.Fab")
		)
		(fp_line
			(start -0.12065 0.3048)
			(end -0.67945 0.3048)
			(stroke
				(width 0.1)
				(type default)
			)
			(layer "F.Fab")
		)
		(fp_line
			(start -0.67945 0.3048)
			(end -0.67945 -0.305054)
			(stroke
				(width 0.1)
				(type default)
			)
			(layer "F.Fab")
		)
		(pad "1" smd circle
			(at -0.40005 0 90)
			(size 0 0)
			(layers "F.Cu" "F.Mask" "F.Paste")
			(net "SMB_INA230_3V3AUX_SCL")
		)
		(pad "2" smd circle
			(at 0.40005 0 90)
			(size 0 0)
			(layers "F.Cu" "F.Mask" "F.Paste")
			(net "SMB_INA230_1_3V3AUX_SCL_R")
		)
	)
	(footprint ""
		(layer "F.Cu")
		(at 294.365426 -15.414244)
		(property "Reference" "U271"
			(at 3.60934 -2.106168 0)
			(unlocked yes)
			(layer "F.SilkS")
			(effects
				(font
					(size 0.7874 0.5842)
					(thickness 0.1524)
				)
				(justify left)
			)
		)
		(property "Value" ""
			(at 0 0 0)
			(layer "F.Fab")
			(effects
				(font
					(size 1.27 1.27)
				)
			)
		)
		(duplicate_pad_numbers_are_jumpers no)
		(fp_line
			(start -3.447796 -2.500122)
			(end -3.447796 2.500122)
			(stroke
				(width 0.1524)
				(type default)
			)
			(layer "F.SilkS")
		)
		(fp_line
			(start -3.447796 2.500122)
			(end 3.447796 2.500122)
			(stroke
				(width 0.1524)
				(type default)
			)
			(layer "F.SilkS")
		)
		(fp_line
			(start -1.484122 -2.500122)
			(end -3.447796 -2.500122)
			(stroke
				(width 0.1524)
				(type default)
			)
			(layer "F.SilkS")
		)
		(fp_line
			(start 0 -1.016)
			(end -1.484122 -2.500122)
			(stroke
				(width 0.1524)
				(type default)
			)
			(layer "F.SilkS")
		)
		(fp_line
			(start 1.484122 -2.500122)
			(end 0 -1.016)
			(stroke
				(width 0.1524)
				(type default)
			)
			(layer "F.SilkS")
		)
		(fp_line
			(start 3.447796 -2.500122)
			(end 1.484122 -2.500122)
			(stroke
				(width 0.1524)
				(type default)
			)
			(layer "F.SilkS")
		)
		(fp_line
			(start 3.447796 2.500122)
			(end 3.447796 -2.500122)
			(stroke
				(width 0.1524)
				(type default)
			)
			(layer "F.SilkS")
		)
		(fp_poly
			(pts
				(xy -4.5974 -1.397) (xy -4.5974 -2.413) (xy -3.5814 -1.905)
			)
			(stroke
				(width 0)
				(type default)
			)
			(fill yes)
			(layer "F.SilkS")
		)
		(fp_line
			(start -1.999996 -2.500122)
			(end -1.999996 2.500122)
			(stroke
				(width 0.1)
				(type default)
			)
			(layer "F.Fab")
		)
		(fp_line
			(start -1.999996 2.500122)
			(end 1.999996 2.500122)
			(stroke
				(width 0.1)
				(type default)
			)
			(layer "F.Fab")
		)
		(fp_line
			(start 1.999996 -2.500122)
			(end -1.999996 -2.500122)
			(stroke
				(width 0.1)
				(type default)
			)
			(layer "F.Fab")
		)
		(fp_line
			(start 1.999996 2.500122)
			(end 1.999996 -2.500122)
			(stroke
				(width 0.1)
				(type default)
			)
			(layer "F.Fab")
		)
		(fp_poly
			(pts
				(xy -4.5974 -2.413) (xy -4.5974 -1.397) (xy -3.5814 -1.905)
			)
			(stroke
				(width 0)
				(type default)
			)
			(fill yes)
			(layer "F.Fab")
		)
		(pad "1" smd rect
			(at -2.649982 -1.905 270)
			(size 0.6096 1.3208)
			(layers "F.Cu" "F.Mask" "F.Paste")
			(net "SMB_LM75_1_3V3AUX_SDA_R1")
		)
		(pad "2" smd rect
			(at -2.649982 -0.635 270)
			(size 0.6096 1.3208)
			(layers "F.Cu" "F.Mask" "F.Paste")
			(net "SMB_LM75_1_3V3AUX_SCL_R1")
		)
		(pad "3" smd rect
			(at -2.649982 0.635 270)
			(size 0.6096 1.3208)
			(layers "F.Cu" "F.Mask" "F.Paste")
			(net "FM_G751_1_ALERT_N")
		)
		(pad "4" smd rect
			(at -2.649982 1.905 270)
			(size 0.6096 1.3208)
			(layers "F.Cu" "F.Mask" "F.Paste")
			(net "GND")
		)
		(pad "5" smd rect
			(at 2.649982 1.905 270)
			(size 0.6096 1.3208)
			(layers "F.Cu" "F.Mask" "F.Paste")
			(net "U271_1_ADD2")
		)
		(pad "6" smd rect
			(at 2.649982 0.635 270)
			(size 0.6096 1.3208)
			(layers "F.Cu" "F.Mask" "F.Paste")
			(net "U271_1_ADD1")
		)
		(pad "7" smd rect
			(at 2.649982 -0.635 270)
			(size 0.6096 1.3208)
			(layers "F.Cu" "F.Mask" "F.Paste")
			(net "U271_1_ADD0")
		)
		(pad "8" smd rect
			(at 2.649982 -1.905 270)
			(size 0.6096 1.3208)
			(layers "F.Cu" "F.Mask" "F.Paste")
			(net "P3V3_AUX")
		)
	)
	(footprint ""
		(layer "F.Cu")
		(at 395.794738 -395.1732 90)
		(property "Reference" "R1100"
			(at 0 0 90)
			(layer "F.SilkS")
			(hide yes)
			(effects
				(font
					(size 1.27 1.27)
				)
			)
		)
		(property "Value" ""
			(at 0 0 90)
			(layer "F.Fab")
			(effects
				(font
					(size 1.27 1.27)
				)
			)
		)
		(duplicate_pad_numbers_are_jumpers no)
		(fp_line
			(start 0.32512 -0.175006)
			(end 0.32512 0.175006)
			(stroke
				(width 0.1)
				(type default)
			)
			(layer "F.Fab")
		)
		(fp_line
			(start -0.32512 -0.175006)
			(end 0.32512 -0.175006)
			(stroke
				(width 0.1)
				(type default)
			)
			(layer "F.Fab")
		)
		(fp_line
			(start 0.32512 0.175006)
			(end -0.32512 0.175006)
			(stroke
				(width 0.1)
				(type default)
			)
			(layer "F.Fab")
		)
		(fp_line
			(start -0.32512 0.175006)
			(end -0.32512 -0.175006)
			(stroke
				(width 0.1)
				(type default)
			)
			(layer "F.Fab")
		)
		(pad "1" smd rect
			(at -0.2667 0 90)
			(size 0.3048 0.381)
			(layers "F.Cu" "F.Mask" "F.Paste")
			(net "RT_CPU0_P3_ADDR2")
		)
		(pad "2" smd rect
			(at 0.2667 0 270)
			(size 0.3048 0.381)
			(layers "F.Cu" "F.Mask" "F.Paste")
			(net "GND")
		)
	)
)
